# BASEBOARD_FAB2 (Tioga Pass) — schematic netlist excerpt (pin names and nets, part order shuffled) for the footprints in the layout excerpt that follows; sources: Cadence DE-HDL packaged netlist, KiCad conversion of Wiwynn_Tioga_Pass_MB.brd

R25W1  120R2F-GP  1%  pkg RCL_GP  page 151 : \1\ = GND ; \2\ = BMC_M_CKE
R1W29  RES  0.0 5% CHIP  pkg 0402  page 191 : A = RST_BMC_SYSRST_BTN_OUT_B_N ; B = RST_BMC_SYSRST_BTN_OUT_B_R1_N
C9T4  CAP  10UF 16V 10% X6S  pkg 0805  page 224 : A = VR_FET_SW_P12V_STBY_PVDDQ_GHJ ; B = GND

(kicad_pcb
	(version 20260206)
	(generator "pcbnew")
	(generator_version "10.0")
	(general
		(thickness 1.6)
		(legacy_teardrops no)
	)
	(paper "A4")
	(title_block
		(title "Wiwynn_Tioga_Pass_MB.brd")
		(comment 1 "Tioga Pass / footprints 3503-3505 of 4770")
	)
	(layers
		(0 "F.Cu" signal "TOP")
		(4 "In1.Cu" signal "L2GND")
		(6 "In2.Cu" signal "L3")
		(8 "In3.Cu" signal "L4GND")
		(10 "In4.Cu" signal "L5")
		(12 "In5.Cu" signal "L6GND")
		(14 "In6.Cu" signal "L7VCC")
		(16 "In7.Cu" signal "L8VCC")
		(18 "In8.Cu" signal "L9GND")
		(20 "In9.Cu" signal "L10")
		(22 "In10.Cu" signal "L11GND")
		(24 "In11.Cu" signal "L12")
		(26 "In12.Cu" signal "L13GND")
		(2 "B.Cu" signal "BOTTOM")
		(9 "F.Adhes" user "F.Adhesive")
		(11 "B.Adhes" user "B.Adhesive")
		(13 "F.Paste" user "Package Geometry/Pastemask Top")
		(15 "B.Paste" user "Package Geometry/Pastemask Bottom")
		(5 "F.SilkS" user "Ref Des/Silkscreen Top")
		(7 "B.SilkS" user "Ref Des/Silkscreen Bottom")
		(1 "F.Mask" user "Board Geometry/Soldermask Top")
		(3 "B.Mask" user "Board Geometry/Soldermask Bottom")
		(17 "Dwgs.User" user "User.Drawings")
		(19 "Cmts.User" user "User.Comments")
		(21 "Eco1.User" user "User.Eco1")
		(23 "Eco2.User" user "User.Eco2")
		(25 "Edge.Cuts" user "Board Geometry/Outline")
		(27 "Margin" user)
		(31 "F.CrtYd" user "Package Geometry/Place Bound Top")
		(29 "B.CrtYd" user "Package Geometry/Place Bound Bottom")
		(35 "F.Fab" user "Ref Des/Assembly Top")
		(33 "B.Fab" user "Ref Des/Assembly Bottom")
	)
	(footprint ""
		(layer "B.Cu")
		(at 446.381632 -32.4485 90)
		(property "Reference" "R25W1"
			(at 0 0 90)
			(layer "B.SilkS")
			(hide yes)
			(effects
				(font
					(size 1.27 1.27)
				)
				(justify mirror)
			)
		)
		(property "Value" "*"
			(at -0.064008 -4.108196 90)
			(unlocked yes)
			(layer "B.Fab")
			(hide yes)
			(effects
				(font
					(size 1.27 1.016)
					(thickness 0.1524)
				)
				(justify mirror)
			)
		)
		(property "Device Type" "120R2F-GP_RCL_GP-120R2F-GP,64.A"
			(at -0.064008 -5.632196 90)
			(unlocked yes)
			(layer "B.Fab")
			(hide yes)
			(effects
				(font
					(size 1.27 1.016)
					(thickness 0.1524)
				)
				(justify mirror)
			)
		)
		(duplicate_pad_numbers_are_jumpers no)
		(fp_line
			(start 0.508 -0.9398)
			(end 0.508 0.9398)
			(stroke
				(width 0.1524)
				(type default)
			)
			(layer "B.SilkS")
		)
		(fp_line
			(start -0.508 -0.9398)
			(end 0.508 -0.9398)
			(stroke
				(width 0.1524)
				(type default)
			)
			(layer "B.SilkS")
		)
		(fp_rect
			(start 0.508 0.9398)
			(end -0.508 -0.9398)
			(stroke
				(width 0)
				(type default)
			)
			(fill no)
			(layer "B.CrtYd")
		)
		(fp_rect
			(start 0.508 0.9398)
			(end -0.508 -0.9398)
			(stroke
				(width 0)
				(type default)
			)
			(fill no)
			(layer "B.Fab")
		)
		(pad "1" smd custom
			(at 0 -0.4445 270)
			(size 0.1397 0.1397)
			(layers "B.Cu" "B.Mask" "B.Paste")
			(net "GND")
			(options
				(clearance outline)
				(anchor circle)
			)
			(primitives
				(gr_poly
					(pts
						(arc
							(start -0.1778 0.2794)
							(mid -0.249642 0.249642)
							(end -0.2794 0.1778)
						)
						(arc
							(start -0.2794 -0.1778)
							(mid -0.249642 -0.249642)
							(end -0.1778 -0.2794)
						)
						(arc
							(start 0.1778 -0.2794)
							(mid 0.249642 -0.249642)
							(end 0.2794 -0.1778)
						)
						(arc
							(start 0.2794 0.1778)
							(mid 0.249642 0.249642)
							(end 0.1778 0.2794)
						)
					)
					(width 0)
					(fill yes)
				)
			)
		)
		(pad "2" smd custom
			(at 0 0.4445 270)
			(size 0.1397 0.1397)
			(layers "B.Cu" "B.Mask" "B.Paste")
			(net "BMC_M_CKE")
			(options
				(clearance outline)
				(anchor circle)
			)
			(primitives
				(gr_poly
					(pts
						(arc
							(start -0.1778 0.2794)
							(mid -0.249642 0.249642)
							(end -0.2794 0.1778)
						)
						(arc
							(start -0.2794 -0.1778)
							(mid -0.249642 -0.249642)
							(end -0.1778 -0.2794)
						)
						(arc
							(start 0.1778 -0.2794)
							(mid 0.249642 -0.249642)
							(end 0.2794 -0.1778)
						)
						(arc
							(start 0.2794 0.1778)
							(mid 0.249642 0.249642)
							(end 0.1778 0.2794)
						)
					)
					(width 0)
					(fill yes)
				)
			)
		)
	)
	(footprint ""
		(layer "B.Cu")
		(at 3.893312 -20.237196 90)
		(property "Reference" "C9T4"
			(at 0 0 90)
			(layer "B.SilkS")
			(hide yes)
			(effects
				(font
					(size 1.27 1.27)
				)
				(justify mirror)
			)
		)
		(property "Value" ""
			(at 0 0 90)
			(layer "B.Fab")
			(effects
				(font
					(size 1.27 1.27)
				)
				(justify mirror)
			)
		)
		(duplicate_pad_numbers_are_jumpers no)
		(fp_rect
			(start -0.7239 -0.2159)
			(end 0.7239 1.9939)
			(stroke
				(width 0)
				(type default)
			)
			(fill no)
			(layer "B.CrtYd")
		)
		(fp_line
			(start 0.7239 -0.2159)
			(end 0.7239 1.9939)
			(stroke
				(width 0.1)
				(type default)
			)
			(layer "B.Fab")
		)
		(fp_line
			(start -0.7239 -0.2159)
			(end 0.7239 -0.2159)
			(stroke
				(width 0.1)
				(type default)
			)
			(layer "B.Fab")
		)
		(fp_line
			(start 0.7239 1.9939)
			(end -0.7239 1.9939)
			(stroke
				(width 0.1)
				(type default)
			)
			(layer "B.Fab")
		)
		(fp_line
			(start -0.7239 1.9939)
			(end -0.7239 -0.2159)
			(stroke
				(width 0.1)
				(type default)
			)
			(layer "B.Fab")
		)
		(pad "1" smd rect
			(at 0 0 270)
			(size 1.27 1.016)
			(layers "B.Cu" "B.Mask" "B.Paste")
			(net "VR_FET_SW_P12V_STBY_PVDDQ_GHJ")
		)
		(pad "2" smd rect
			(at 0 1.778 270)
			(size 1.27 1.016)
			(layers "B.Cu" "B.Mask" "B.Paste")
			(net "GND")
		)
		(zone
			(layer "B.Cu")
			(hatch none 0.5)
			(connect_pads
				(clearance 0)
			)
			(min_thickness 0.25)
			(keepout
				(tracks not_allowed)
				(vias allowed)
				(pads allowed)
				(copperpour not_allowed)
				(footprints allowed)
			)
			(placement
				(enabled no)
				(sheetname "")
			)
			(fill
				(thermal_gap 0.5)
				(thermal_bridge_width 0.5)
				(island_removal_mode 0)
			)
			(polygon
				(pts
					(xy 4.401312 -19.602196) (xy 5.163312 -19.602196) (xy 5.163312 -20.872196) (xy 4.401312 -20.872196)
				)
			)
		)
	)
	(footprint ""
		(layer "B.Cu")
		(at 398.860518 -61.894974 -90)
		(property "Reference" "R1W29"
			(at 0.8382 -0.67818 270)
			(unlocked yes)
			(layer "B.SilkS")
			(effects
				(font
					(size 0.4064 0.254)
					(thickness 0.1524)
				)
				(justify left mirror)
			)
		)
		(property "Value" ""
			(at 0 0 90)
			(layer "B.Fab")
			(effects
				(font
					(size 1.27 1.27)
				)
				(justify mirror)
			)
		)
		(duplicate_pad_numbers_are_jumpers no)
		(fp_poly
			(pts
				(xy 0.2794 -0.1016) (xy -0.2794 -0.1016) (xy -0.2794 0.9906) (xy 0.2794 0.9906)
			)
			(stroke
				(width 0)
				(type default)
			)
			(fill no)
			(layer "B.CrtYd")
		)
		(fp_line
			(start -0.2794 0.9906)
			(end -0.2794 -0.1016)
			(stroke
				(width 0.1)
				(type default)
			)
			(layer "B.Fab")
		)
		(fp_line
			(start 0.2794 0.9906)
			(end -0.2794 0.9906)
			(stroke
				(width 0.1)
				(type default)
			)
			(layer "B.Fab")
		)
		(fp_line
			(start -0.2794 -0.1016)
			(end 0.2794 -0.1016)
			(stroke
				(width 0.1)
				(type default)
			)
			(layer "B.Fab")
		)
		(fp_line
			(start 0.2794 -0.1016)
			(end 0.2794 0.9906)
			(stroke
				(width 0.1)
				(type default)
			)
			(layer "B.Fab")
		)
		(pad "1" smd rect
			(at 0 0 90)
			(size 0.508 0.508)
			(layers "B.Cu" "B.Mask" "B.Paste")
			(net "RST_BMC_SYSRST_BTN_OUT_B_N")
		)
		(pad "2" smd rect
			(at 0 0.889 90)
			(size 0.508 0.508)
			(layers "B.Cu" "B.Mask" "B.Paste")
			(net "RST_BMC_SYSRST_BTN_OUT_B_R1_N")
		)
		(zone
			(layer "B.Cu")
			(hatch none 0.5)
			(connect_pads
				(clearance 0)
			)
			(min_thickness 0.25)
			(keepout
				(tracks not_allowed)
				(vias allowed)
				(pads allowed)
				(copperpour not_allowed)
				(footprints allowed)
			)
			(placement
				(enabled no)
				(sheetname "")
			)
			(fill
				(thermal_gap 0.5)
				(thermal_bridge_width 0.5)
				(island_removal_mode 0)
			)
			(polygon
				(pts
					(xy 398.225518 -61.640974) (xy 398.225518 -62.148974) (xy 398.606518 -62.148974) (xy 398.606518 -61.640974)
				)
			)
		)
		(zone
			(layer "B.Cu")
			(hatch none 0.5)
			(connect_pads
				(clearance 0)
			)
			(min_thickness 0.25)
			(keepout
				(tracks allowed)
				(vias not_allowed)
				(pads allowed)
				(copperpour not_allowed)
				(footprints allowed)
			)
			(placement
				(enabled no)
				(sheetname "")
			)
			(fill
				(thermal_gap 0.5)
				(thermal_bridge_width 0.5)
				(island_removal_mode 0)
			)
			(polygon
				(pts
					(xy 398.606518 -61.640974) (xy 398.606518 -62.148974) (xy 398.225518 -62.148974) (xy 398.225518 -61.640974)
				)
			)
		)
	)
)
